(kicad_pcb
	(version 20260206)
	(generator "pcbnew")
	(generator_version "10.0")
	(general
		(thickness 1.6)
		(legacy_teardrops no)
	)
	(paper "A4")
	(title_block
		(title "01162023_DA0F0TEBIF0_F0T_Expander_BD_F_brd_V02_OCP.brd")
		(comment 1 "Grand Teton / footprints 7822-7830 of 9728")
	)
	(layers
		(0 "F.Cu" signal "TOP")
		(4 "In1.Cu" signal "GND")
		(6 "In2.Cu" signal "VCC")
		(8 "In3.Cu" signal "VCC1")
		(10 "In4.Cu" signal "GND1")
		(12 "In5.Cu" signal "IN1")
		(14 "In6.Cu" signal "GND2")
		(16 "In7.Cu" signal "IN2")
		(18 "In8.Cu" signal "GND3")
		(20 "In9.Cu" signal "IN3")
		(22 "In10.Cu" signal "GND4")
		(24 "In11.Cu" signal "IN4")
		(26 "In12.Cu" signal "GND5")
		(28 "In13.Cu" signal "IN5")
		(30 "In14.Cu" signal "GND6")
		(32 "In15.Cu" signal "IN6")
		(34 "In16.Cu" signal "GND7")
		(2 "B.Cu" signal "BOTTOM")
		(9 "F.Adhes" user "F.Adhesive")
		(11 "B.Adhes" user "B.Adhesive")
		(13 "F.Paste" user "Package Geometry/Pastemask Top")
		(15 "B.Paste" user "Package Geometry/Pastemask Bottom")
		(5 "F.SilkS" user "Ref Des/Silkscreen Top")
		(7 "B.SilkS" user "Ref Des/Silkscreen Bottom")
		(1 "F.Mask" user "Board Geometry/Soldermask Top")
		(3 "B.Mask" user "Board Geometry/Soldermask Bottom")
		(17 "Dwgs.User" user "User.Drawings")
		(19 "Cmts.User" user "User.Comments")
		(21 "Eco1.User" user "User.Eco1")
		(23 "Eco2.User" user "User.Eco2")
		(25 "Edge.Cuts" user "Board Geometry/Outline")
		(27 "Margin" user)
		(31 "F.CrtYd" user "Package Geometry/Place Bound Top")
		(29 "B.CrtYd" user "Package Geometry/Place Bound Bottom")
		(35 "F.Fab" user "Ref Des/Assembly Top")
		(33 "B.Fab" user "Ref Des/Assembly Bottom")
	)
	(footprint ""
		(layer "B.Cu")
		(at 293.301166 -305.399948 -90)
		(property "Reference" "C3322"
			(at 0 0 90)
			(layer "B.SilkS")
			(hide yes)
			(effects
				(font
					(size 1.27 1.27)
				)
				(justify mirror)
			)
		)
		(property "Value" ""
			(at 0 0 90)
			(layer "B.Fab")
			(effects
				(font
					(size 1.27 1.27)
				)
				(justify mirror)
			)
		)
		(duplicate_pad_numbers_are_jumpers no)
		(fp_line
			(start -0.299974 0.150114)
			(end 0.299974 0.150114)
			(stroke
				(width 0.1)
				(type default)
			)
			(layer "B.Fab")
		)
		(fp_line
			(start 0.299974 0.150114)
			(end 0.299974 -0.150114)
			(stroke
				(width 0.1)
				(type default)
			)
			(layer "B.Fab")
		)
		(fp_line
			(start -0.299974 -0.150114)
			(end -0.299974 0.150114)
			(stroke
				(width 0.1)
				(type default)
			)
			(layer "B.Fab")
		)
		(fp_line
			(start 0.299974 -0.150114)
			(end -0.299974 -0.150114)
			(stroke
				(width 0.1)
				(type default)
			)
			(layer "B.Fab")
		)
		(pad "1" smd rect
			(at 0.2667 0 90)
			(size 0.3048 0.381)
			(layers "B.Cu" "B.Mask" "B.Paste")
			(net "P1V25_SERDES_VDDPLL_PEX2")
		)
		(pad "2" smd rect
			(at -0.2667 0 90)
			(size 0.3048 0.381)
			(layers "B.Cu" "B.Mask" "B.Paste")
			(net "GND")
		)
	)
	(footprint ""
		(layer "B.Cu")
		(at 55.849774 -299.699934 -90)
		(property "Reference" "C1216"
			(at 0 0 90)
			(layer "B.SilkS")
			(hide yes)
			(effects
				(font
					(size 1.27 1.27)
				)
				(justify mirror)
			)
		)
		(property "Value" ""
			(at 0 0 90)
			(layer "B.Fab")
			(effects
				(font
					(size 1.27 1.27)
				)
				(justify mirror)
			)
		)
		(duplicate_pad_numbers_are_jumpers no)
		(fp_line
			(start -0.299974 0.150114)
			(end 0.299974 0.150114)
			(stroke
				(width 0.1)
				(type default)
			)
			(layer "B.Fab")
		)
		(fp_line
			(start 0.299974 0.150114)
			(end 0.299974 -0.150114)
			(stroke
				(width 0.1)
				(type default)
			)
			(layer "B.Fab")
		)
		(fp_line
			(start -0.299974 -0.150114)
			(end -0.299974 0.150114)
			(stroke
				(width 0.1)
				(type default)
			)
			(layer "B.Fab")
		)
		(fp_line
			(start 0.299974 -0.150114)
			(end -0.299974 -0.150114)
			(stroke
				(width 0.1)
				(type default)
			)
			(layer "B.Fab")
		)
		(pad "1" smd rect
			(at 0.2667 0 90)
			(size 0.3048 0.381)
			(layers "B.Cu" "B.Mask" "B.Paste")
			(net "P0V8_SERDES_VDDA_PEX0")
		)
		(pad "2" smd rect
			(at -0.2667 0 90)
			(size 0.3048 0.381)
			(layers "B.Cu" "B.Mask" "B.Paste")
			(net "GND")
		)
	)
	(footprint ""
		(layer "B.Cu")
		(at 224.501964 -208.78546 -90)
		(property "Reference" "R4898"
			(at 0 0 90)
			(layer "B.SilkS")
			(hide yes)
			(effects
				(font
					(size 1.27 1.27)
				)
				(justify mirror)
			)
		)
		(property "Value" ""
			(at 0 0 90)
			(layer "B.Fab")
			(effects
				(font
					(size 1.27 1.27)
				)
				(justify mirror)
			)
		)
		(duplicate_pad_numbers_are_jumpers no)
		(fp_line
			(start -0.7874 0.4064)
			(end 0.7874 0.4064)
			(stroke
				(width 0.1524)
				(type default)
			)
			(layer "B.SilkS")
		)
		(fp_line
			(start 0.7874 0.4064)
			(end 0.7874 -0.4064)
			(stroke
				(width 0.1524)
				(type default)
			)
			(layer "B.SilkS")
		)
		(fp_line
			(start -0.7874 -0.4064)
			(end -0.7874 0.4064)
			(stroke
				(width 0.1524)
				(type default)
			)
			(layer "B.SilkS")
		)
		(fp_line
			(start 0.7874 -0.4064)
			(end -0.7874 -0.4064)
			(stroke
				(width 0.1524)
				(type default)
			)
			(layer "B.SilkS")
		)
		(fp_line
			(start -0.67945 0.3048)
			(end -0.120396 0.3048)
			(stroke
				(width 0.1)
				(type default)
			)
			(layer "B.Fab")
		)
		(fp_line
			(start -0.120396 0.3048)
			(end -0.120396 0.2794)
			(stroke
				(width 0.1)
				(type default)
			)
			(layer "B.Fab")
		)
		(fp_line
			(start 0.12065 0.3048)
			(end 0.67945 0.3048)
			(stroke
				(width 0.1)
				(type default)
			)
			(layer "B.Fab")
		)
		(fp_line
			(start 0.67945 0.3048)
			(end 0.67945 -0.305054)
			(stroke
				(width 0.1)
				(type default)
			)
			(layer "B.Fab")
		)
		(fp_line
			(start -0.120396 0.2794)
			(end 0.12065 0.2794)
			(stroke
				(width 0.1)
				(type default)
			)
			(layer "B.Fab")
		)
		(fp_line
			(start 0.12065 0.2794)
			(end 0.12065 0.3048)
			(stroke
				(width 0.1)
				(type default)
			)
			(layer "B.Fab")
		)
		(fp_line
			(start -0.12065 -0.2794)
			(end -0.12065 -0.3048)
			(stroke
				(width 0.1)
				(type default)
			)
			(layer "B.Fab")
		)
		(fp_line
			(start 0.12065 -0.2794)
			(end -0.12065 -0.2794)
			(stroke
				(width 0.1)
				(type default)
			)
			(layer "B.Fab")
		)
		(fp_line
			(start -0.67945 -0.3048)
			(end -0.67945 0.3048)
			(stroke
				(width 0.1)
				(type default)
			)
			(layer "B.Fab")
		)
		(fp_line
			(start -0.12065 -0.3048)
			(end -0.67945 -0.3048)
			(stroke
				(width 0.1)
				(type default)
			)
			(layer "B.Fab")
		)
		(fp_line
			(start 0.12065 -0.305054)
			(end 0.12065 -0.2794)
			(stroke
				(width 0.1)
				(type default)
			)
			(layer "B.Fab")
		)
		(fp_line
			(start 0.67945 -0.305054)
			(end 0.12065 -0.305054)
			(stroke
				(width 0.1)
				(type default)
			)
			(layer "B.Fab")
		)
		(pad "1" smd circle
			(at 0.40005 0 90)
			(size 0 0)
			(layers "B.Cu" "B.Mask" "B.Paste")
			(net "JTAG_BIC_EN_R")
		)
		(pad "2" smd circle
			(at -0.40005 0 90)
			(size 0 0)
			(layers "B.Cu" "B.Mask" "B.Paste")
			(net "JTAG_BIC_EN")
		)
	)
	(footprint ""
		(layer "B.Cu")
		(at 46.355 -299.212)
		(property "Reference" "C3026"
			(at 0 0 0)
			(layer "B.SilkS")
			(hide yes)
			(effects
				(font
					(size 1.27 1.27)
				)
				(justify mirror)
			)
		)
		(property "Value" ""
			(at 0 0 0)
			(layer "B.Fab")
			(effects
				(font
					(size 1.27 1.27)
				)
				(justify mirror)
			)
		)
		(duplicate_pad_numbers_are_jumpers no)
		(fp_line
			(start -0.299974 -0.150114)
			(end -0.299974 0.150114)
			(stroke
				(width 0.1)
				(type default)
			)
			(layer "B.Fab")
		)
		(fp_line
			(start -0.299974 0.150114)
			(end 0.299974 0.150114)
			(stroke
				(width 0.1)
				(type default)
			)
			(layer "B.Fab")
		)
		(fp_line
			(start 0.299974 -0.150114)
			(end -0.299974 -0.150114)
			(stroke
				(width 0.1)
				(type default)
			)
			(layer "B.Fab")
		)
		(fp_line
			(start 0.299974 0.150114)
			(end 0.299974 -0.150114)
			(stroke
				(width 0.1)
				(type default)
			)
			(layer "B.Fab")
		)
		(pad "1" smd rect
			(at 0.2667 0 180)
			(size 0.3048 0.381)
			(layers "B.Cu" "B.Mask" "B.Paste")
			(net "PCEPLL1_VDDA18_PEX0")
		)
		(pad "2" smd rect
			(at -0.2667 0 180)
			(size 0.3048 0.381)
			(layers "B.Cu" "B.Mask" "B.Paste")
			(net "GND")
		)
	)
	(footprint ""
		(layer "B.Cu")
		(at 227.549964 -208.78546 -90)
		(property "Reference" "R4895"
			(at 0 0 90)
			(layer "B.SilkS")
			(hide yes)
			(effects
				(font
					(size 1.27 1.27)
				)
				(justify mirror)
			)
		)
		(property "Value" ""
			(at 0 0 90)
			(layer "B.Fab")
			(effects
				(font
					(size 1.27 1.27)
				)
				(justify mirror)
			)
		)
		(duplicate_pad_numbers_are_jumpers no)
		(fp_line
			(start -0.7874 0.4064)
			(end 0.7874 0.4064)
			(stroke
				(width 0.1524)
				(type default)
			)
			(layer "B.SilkS")
		)
		(fp_line
			(start 0.7874 0.4064)
			(end 0.7874 -0.4064)
			(stroke
				(width 0.1524)
				(type default)
			)
			(layer "B.SilkS")
		)
		(fp_line
			(start -0.7874 -0.4064)
			(end -0.7874 0.4064)
			(stroke
				(width 0.1524)
				(type default)
			)
			(layer "B.SilkS")
		)
		(fp_line
			(start 0.7874 -0.4064)
			(end -0.7874 -0.4064)
			(stroke
				(width 0.1524)
				(type default)
			)
			(layer "B.SilkS")
		)
		(fp_line
			(start -0.67945 0.3048)
			(end -0.120396 0.3048)
			(stroke
				(width 0.1)
				(type default)
			)
			(layer "B.Fab")
		)
		(fp_line
			(start -0.120396 0.3048)
			(end -0.120396 0.2794)
			(stroke
				(width 0.1)
				(type default)
			)
			(layer "B.Fab")
		)
		(fp_line
			(start 0.12065 0.3048)
			(end 0.67945 0.3048)
			(stroke
				(width 0.1)
				(type default)
			)
			(layer "B.Fab")
		)
		(fp_line
			(start 0.67945 0.3048)
			(end 0.67945 -0.305054)
			(stroke
				(width 0.1)
				(type default)
			)
			(layer "B.Fab")
		)
		(fp_line
			(start -0.120396 0.2794)
			(end 0.12065 0.2794)
			(stroke
				(width 0.1)
				(type default)
			)
			(layer "B.Fab")
		)
		(fp_line
			(start 0.12065 0.2794)
			(end 0.12065 0.3048)
			(stroke
				(width 0.1)
				(type default)
			)
			(layer "B.Fab")
		)
		(fp_line
			(start -0.12065 -0.2794)
			(end -0.12065 -0.3048)
			(stroke
				(width 0.1)
				(type default)
			)
			(layer "B.Fab")
		)
		(fp_line
			(start 0.12065 -0.2794)
			(end -0.12065 -0.2794)
			(stroke
				(width 0.1)
				(type default)
			)
			(layer "B.Fab")
		)
		(fp_line
			(start -0.67945 -0.3048)
			(end -0.67945 0.3048)
			(stroke
				(width 0.1)
				(type default)
			)
			(layer "B.Fab")
		)
		(fp_line
			(start -0.12065 -0.3048)
			(end -0.67945 -0.3048)
			(stroke
				(width 0.1)
				(type default)
			)
			(layer "B.Fab")
		)
		(fp_line
			(start 0.12065 -0.305054)
			(end 0.12065 -0.2794)
			(stroke
				(width 0.1)
				(type default)
			)
			(layer "B.Fab")
		)
		(fp_line
			(start 0.67945 -0.305054)
			(end 0.12065 -0.305054)
			(stroke
				(width 0.1)
				(type default)
			)
			(layer "B.Fab")
		)
		(pad "1" smd circle
			(at 0.40005 0 90)
			(size 0 0)
			(layers "B.Cu" "B.Mask" "B.Paste")
			(net "JTAG_BIC_TCK_R")
		)
		(pad "2" smd circle
			(at -0.40005 0 90)
			(size 0 0)
			(layers "B.Cu" "B.Mask" "B.Paste")
			(net "JTAG_BIC_TCK")
		)
	)
	(footprint ""
		(layer "B.Cu")
		(at 350.598994 -324.936358 -90)
		(property "Reference" "C4367"
			(at 0 0 90)
			(layer "B.SilkS")
			(hide yes)
			(effects
				(font
					(size 1.27 1.27)
				)
				(justify mirror)
			)
		)
		(property "Value" ""
			(at 0 0 90)
			(layer "B.Fab")
			(effects
				(font
					(size 1.27 1.27)
				)
				(justify mirror)
			)
		)
		(duplicate_pad_numbers_are_jumpers no)
		(fp_line
			(start -1.2954 0.5842)
			(end 1.2954 0.5842)
			(stroke
				(width 0.1524)
				(type default)
			)
			(layer "B.SilkS")
		)
		(fp_line
			(start 1.2954 0.5842)
			(end 1.2954 -0.5842)
			(stroke
				(width 0.1524)
				(type default)
			)
			(layer "B.SilkS")
		)
		(fp_line
			(start -1.2954 -0.5842)
			(end -1.2954 0.5842)
			(stroke
				(width 0.1524)
				(type default)
			)
			(layer "B.SilkS")
		)
		(fp_line
			(start 1.2954 -0.5842)
			(end -1.2954 -0.5842)
			(stroke
				(width 0.1524)
				(type default)
			)
			(layer "B.SilkS")
		)
		(fp_line
			(start -0.8636 0.4572)
			(end 0.8636 0.4572)
			(stroke
				(width 0.1)
				(type default)
			)
			(layer "B.Fab")
		)
		(fp_line
			(start 0.8636 0.4572)
			(end 0.8636 0.4064)
			(stroke
				(width 0.1)
				(type default)
			)
			(layer "B.Fab")
		)
		(fp_line
			(start -1.1938 0.4064)
			(end -0.8636 0.4064)
			(stroke
				(width 0.1)
				(type default)
			)
			(layer "B.Fab")
		)
		(fp_line
			(start -0.8636 0.4064)
			(end -0.8636 0.4572)
			(stroke
				(width 0.1)
				(type default)
			)
			(layer "B.Fab")
		)
		(fp_line
			(start 0.8636 0.4064)
			(end 1.1938 0.4064)
			(stroke
				(width 0.1)
				(type default)
			)
			(layer "B.Fab")
		)
		(fp_line
			(start 1.1938 0.4064)
			(end 1.1938 -0.4064)
			(stroke
				(width 0.1)
				(type default)
			)
			(layer "B.Fab")
		)
		(fp_line
			(start -1.1938 -0.4064)
			(end -1.1938 0.4064)
			(stroke
				(width 0.1)
				(type default)
			)
			(layer "B.Fab")
		)
		(fp_line
			(start -0.8636 -0.4064)
			(end -1.1938 -0.4064)
			(stroke
				(width 0.1)
				(type default)
			)
			(layer "B.Fab")
		)
		(fp_line
			(start 0.8636 -0.4064)
			(end 0.8636 -0.4572)
			(stroke
				(width 0.1)
				(type default)
			)
			(layer "B.Fab")
		)
		(fp_line
			(start 1.1938 -0.4064)
			(end 0.8636 -0.4064)
			(stroke
				(width 0.1)
				(type default)
			)
			(layer "B.Fab")
		)
		(fp_line
			(start -0.8636 -0.4572)
			(end -0.8636 -0.4064)
			(stroke
				(width 0.1)
				(type default)
			)
			(layer "B.Fab")
		)
		(fp_line
			(start 0.8636 -0.4572)
			(end -0.8636 -0.4572)
			(stroke
				(width 0.1)
				(type default)
			)
			(layer "B.Fab")
		)
		(pad "1" smd rect
			(at 0.7366 0 180)
			(size 0.7112 0.8128)
			(layers "B.Cu" "B.Mask" "B.Paste")
			(net "P0V8_SERDES_VDDA_PEX3_C1")
		)
		(pad "2" smd rect
			(at -0.7366 0 180)
			(size 0.7112 0.8128)
			(layers "B.Cu" "B.Mask" "B.Paste")
			(net "GND")
		)
	)
	(footprint ""
		(layer "B.Cu")
		(at 102.655878 -390.013444 -90)
		(property "Reference" "C3633"
			(at 0 0 90)
			(layer "B.SilkS")
			(hide yes)
			(effects
				(font
					(size 1.27 1.27)
				)
				(justify mirror)
			)
		)
		(property "Value" ""
			(at 0 0 90)
			(layer "B.Fab")
			(effects
				(font
					(size 1.27 1.27)
				)
				(justify mirror)
			)
		)
		(duplicate_pad_numbers_are_jumpers no)
		(fp_line
			(start -0.7874 0.4064)
			(end 0.7874 0.4064)
			(stroke
				(width 0.1524)
				(type default)
			)
			(layer "B.SilkS")
		)
		(fp_line
			(start 0.7874 0.4064)
			(end 0.7874 -0.4064)
			(stroke
				(width 0.1524)
				(type default)
			)
			(layer "B.SilkS")
		)
		(fp_line
			(start -0.7874 -0.4064)
			(end -0.7874 0.4064)
			(stroke
				(width 0.1524)
				(type default)
			)
			(layer "B.SilkS")
		)
		(fp_line
			(start 0.7874 -0.4064)
			(end -0.7874 -0.4064)
			(stroke
				(width 0.1524)
				(type default)
			)
			(layer "B.SilkS")
		)
		(fp_line
			(start -0.67945 0.3048)
			(end -0.120396 0.3048)
			(stroke
				(width 0.1)
				(type default)
			)
			(layer "B.Fab")
		)
		(fp_line
			(start -0.120396 0.3048)
			(end -0.120396 0.2794)
			(stroke
				(width 0.1)
				(type default)
			)
			(layer "B.Fab")
		)
		(fp_line
			(start 0.12065 0.3048)
			(end 0.67945 0.3048)
			(stroke
				(width 0.1)
				(type default)
			)
			(layer "B.Fab")
		)
		(fp_line
			(start 0.67945 0.3048)
			(end 0.67945 -0.305054)
			(stroke
				(width 0.1)
				(type default)
			)
			(layer "B.Fab")
		)
		(fp_line
			(start -0.120396 0.2794)
			(end 0.12065 0.2794)
			(stroke
				(width 0.1)
				(type default)
			)
			(layer "B.Fab")
		)
		(fp_line
			(start 0.12065 0.2794)
			(end 0.12065 0.3048)
			(stroke
				(width 0.1)
				(type default)
			)
			(layer "B.Fab")
		)
		(fp_line
			(start -0.12065 -0.2794)
			(end -0.12065 -0.3048)
			(stroke
				(width 0.1)
				(type default)
			)
			(layer "B.Fab")
		)
		(fp_line
			(start 0.12065 -0.2794)
			(end -0.12065 -0.2794)
			(stroke
				(width 0.1)
				(type default)
			)
			(layer "B.Fab")
		)
		(fp_line
			(start -0.67945 -0.3048)
			(end -0.67945 0.3048)
			(stroke
				(width 0.1)
				(type default)
			)
			(layer "B.Fab")
		)
		(fp_line
			(start -0.12065 -0.3048)
			(end -0.67945 -0.3048)
			(stroke
				(width 0.1)
				(type default)
			)
			(layer "B.Fab")
		)
		(fp_line
			(start 0.12065 -0.305054)
			(end 0.12065 -0.2794)
			(stroke
				(width 0.1)
				(type default)
			)
			(layer "B.Fab")
		)
		(fp_line
			(start 0.67945 -0.305054)
			(end 0.12065 -0.305054)
			(stroke
				(width 0.1)
				(type default)
			)
			(layer "B.Fab")
		)
		(pad "1" smd circle
			(at 0.40005 0 90)
			(size 0 0)
			(layers "B.Cu" "B.Mask" "B.Paste")
			(net "P3V3_BIC_USB_HUB")
		)
		(pad "2" smd circle
			(at -0.40005 0 90)
			(size 0 0)
			(layers "B.Cu" "B.Mask" "B.Paste")
			(net "GND")
		)
	)
	(footprint ""
		(layer "B.Cu")
		(at 67.249802 -299.699934 -90)
		(property "Reference" "C1170"
			(at 0 0 90)
			(layer "B.SilkS")
			(hide yes)
			(effects
				(font
					(size 1.27 1.27)
				)
				(justify mirror)
			)
		)
		(property "Value" ""
			(at 0 0 90)
			(layer "B.Fab")
			(effects
				(font
					(size 1.27 1.27)
				)
				(justify mirror)
			)
		)
		(duplicate_pad_numbers_are_jumpers no)
		(fp_line
			(start -0.299974 0.150114)
			(end 0.299974 0.150114)
			(stroke
				(width 0.1)
				(type default)
			)
			(layer "B.Fab")
		)
		(fp_line
			(start 0.299974 0.150114)
			(end 0.299974 -0.150114)
			(stroke
				(width 0.1)
				(type default)
			)
			(layer "B.Fab")
		)
		(fp_line
			(start -0.299974 -0.150114)
			(end -0.299974 0.150114)
			(stroke
				(width 0.1)
				(type default)
			)
			(layer "B.Fab")
		)
		(fp_line
			(start 0.299974 -0.150114)
			(end -0.299974 -0.150114)
			(stroke
				(width 0.1)
				(type default)
			)
			(layer "B.Fab")
		)
		(pad "1" smd rect
			(at 0.2667 0 90)
			(size 0.3048 0.381)
			(layers "B.Cu" "B.Mask" "B.Paste")
			(net "P0V8_SERDES_VDDA_PEX0")
		)
		(pad "2" smd rect
			(at -0.2667 0 90)
			(size 0.3048 0.381)
			(layers "B.Cu" "B.Mask" "B.Paste")
			(net "GND")
		)
	)
	(footprint ""
		(layer "B.Cu")
		(at 292.79977 -299.699934 -90)
		(property "Reference" "C1713"
			(at 0 0 90)
			(layer "B.SilkS")
			(hide yes)
			(effects
				(font
					(size 1.27 1.27)
				)
				(justify mirror)
			)
		)
		(property "Value" ""
			(at 0 0 90)
			(layer "B.Fab")
			(effects
				(font
					(size 1.27 1.27)
				)
				(justify mirror)
			)
		)
		(duplicate_pad_numbers_are_jumpers no)
		(fp_line
			(start -0.299974 0.150114)
			(end 0.299974 0.150114)
			(stroke
				(width 0.1)
				(type default)
			)
			(layer "B.Fab")
		)
		(fp_line
			(start 0.299974 0.150114)
			(end 0.299974 -0.150114)
			(stroke
				(width 0.1)
				(type default)
			)
			(layer "B.Fab")
		)
		(fp_line
			(start -0.299974 -0.150114)
			(end -0.299974 0.150114)
			(stroke
				(width 0.1)
				(type default)
			)
			(layer "B.Fab")
		)
		(fp_line
			(start 0.299974 -0.150114)
			(end -0.299974 -0.150114)
			(stroke
				(width 0.1)
				(type default)
			)
			(layer "B.Fab")
		)
		(pad "1" smd rect
			(at 0.2667 0 90)
			(size 0.3048 0.381)
			(layers "B.Cu" "B.Mask" "B.Paste")
			(net "P0V8_SERDES_VDDA_PEX2")
		)
		(pad "2" smd rect
			(at -0.2667 0 90)
			(size 0.3048 0.381)
			(layers "B.Cu" "B.Mask" "B.Paste")
			(net "GND")
		)
	)
)
